# T6G (Grand Teton) — schematic netlist excerpt (pin names and nets, part order shuffled) for the footprints in the layout excerpt that follows; sources: Cadence DE-HDL packaged netlist, KiCad conversion of 04192023_DAF0TMB3IC0_F0TG_MB_C_brd_V02_OCP.brd

R1459  Q_RES  33 5% CHIP  pkg 0402LF  page 259 : A = PWRGD_P12V_MEM_CPU1 ; B = PWRGD_P12V_MEM_CPU1_R
R1659  Q_RES  4.7K 5% EMPTY  pkg 0402LF  page 171 : A = P3V3_AUX ; B = SCM_JTAG_MUX_S0

(kicad_pcb
	(version 20260206)
	(generator "pcbnew")
	(generator_version "10.0")
	(general
		(thickness 1.6)
		(legacy_teardrops no)
	)
	(paper "A4")
	(title_block
		(title "04192023_DAF0TMB3IC0_F0TG_MB_C_brd_V02_OCP.brd")
		(comment 1 "Grand Teton / footprints 4306-4307 of 8354")
	)
	(layers
		(0 "F.Cu" signal "TOP")
		(4 "In1.Cu" signal "GND")
		(6 "In2.Cu" signal "IN1")
		(8 "In3.Cu" signal "GND1")
		(10 "In4.Cu" signal "IN2")
		(12 "In5.Cu" signal "GND2")
		(14 "In6.Cu" signal "IN3")
		(16 "In7.Cu" signal "GND3")
		(18 "In8.Cu" signal "VCC")
		(20 "In9.Cu" signal "VCC1")
		(22 "In10.Cu" signal "GND4")
		(24 "In11.Cu" signal "IN4")
		(26 "In12.Cu" signal "GND5")
		(28 "In13.Cu" signal "IN5")
		(30 "In14.Cu" signal "GND6")
		(32 "In15.Cu" signal "IN6")
		(34 "In16.Cu" signal "GND7")
		(2 "B.Cu" signal "BOTTOM")
		(9 "F.Adhes" user "F.Adhesive")
		(11 "B.Adhes" user "B.Adhesive")
		(13 "F.Paste" user "Package Geometry/Pastemask Top")
		(15 "B.Paste" user "Package Geometry/Pastemask Bottom")
		(5 "F.SilkS" user "Ref Des/Silkscreen Top")
		(7 "B.SilkS" user "Ref Des/Silkscreen Bottom")
		(1 "F.Mask" user "Board Geometry/Soldermask Top")
		(3 "B.Mask" user "Board Geometry/Soldermask Bottom")
		(17 "Dwgs.User" user "User.Drawings")
		(19 "Cmts.User" user "User.Comments")
		(21 "Eco1.User" user "User.Eco1")
		(23 "Eco2.User" user "User.Eco2")
		(25 "Edge.Cuts" user "Board Geometry/Outline")
		(27 "Margin" user)
		(31 "F.CrtYd" user "Package Geometry/Place Bound Top")
		(29 "B.CrtYd" user "Package Geometry/Place Bound Bottom")
		(35 "F.Fab" user "Ref Des/Assembly Top")
		(33 "B.Fab" user "Ref Des/Assembly Bottom")
	)
	(footprint ""
		(layer "F.Cu")
		(at 138.426952 -55.484014)
		(property "Reference" "R1659"
			(at 0 0 0)
			(layer "F.SilkS")
			(hide yes)
			(effects
				(font
					(size 1.27 1.27)
				)
			)
		)
		(property "Value" ""
			(at 0 0 0)
			(layer "F.Fab")
			(effects
				(font
					(size 1.27 1.27)
				)
			)
		)
		(duplicate_pad_numbers_are_jumpers no)
		(fp_line
			(start -0.7874 -0.4064)
			(end 0.7874 -0.4064)
			(stroke
				(width 0.1524)
				(type default)
			)
			(layer "F.SilkS")
		)
		(fp_line
			(start -0.7874 0.4064)
			(end -0.7874 -0.4064)
			(stroke
				(width 0.1524)
				(type default)
			)
			(layer "F.SilkS")
		)
		(fp_line
			(start 0.7874 -0.4064)
			(end 0.7874 0.4064)
			(stroke
				(width 0.1524)
				(type default)
			)
			(layer "F.SilkS")
		)
		(fp_line
			(start 0.7874 0.4064)
			(end -0.7874 0.4064)
			(stroke
				(width 0.1524)
				(type default)
			)
			(layer "F.SilkS")
		)
		(fp_line
			(start -0.67945 -0.305054)
			(end -0.12065 -0.305054)
			(stroke
				(width 0.1)
				(type default)
			)
			(layer "F.Fab")
		)
		(fp_line
			(start -0.67945 0.3048)
			(end -0.67945 -0.305054)
			(stroke
				(width 0.1)
				(type default)
			)
			(layer "F.Fab")
		)
		(fp_line
			(start -0.12065 -0.305054)
			(end -0.12065 -0.2794)
			(stroke
				(width 0.1)
				(type default)
			)
			(layer "F.Fab")
		)
		(fp_line
			(start -0.12065 -0.2794)
			(end 0.12065 -0.2794)
			(stroke
				(width 0.1)
				(type default)
			)
			(layer "F.Fab")
		)
		(fp_line
			(start -0.12065 0.2794)
			(end -0.12065 0.3048)
			(stroke
				(width 0.1)
				(type default)
			)
			(layer "F.Fab")
		)
		(fp_line
			(start -0.12065 0.3048)
			(end -0.67945 0.3048)
			(stroke
				(width 0.1)
				(type default)
			)
			(layer "F.Fab")
		)
		(fp_line
			(start 0.120396 0.2794)
			(end -0.12065 0.2794)
			(stroke
				(width 0.1)
				(type default)
			)
			(layer "F.Fab")
		)
		(fp_line
			(start 0.120396 0.3048)
			(end 0.120396 0.2794)
			(stroke
				(width 0.1)
				(type default)
			)
			(layer "F.Fab")
		)
		(fp_line
			(start 0.12065 -0.3048)
			(end 0.67945 -0.3048)
			(stroke
				(width 0.1)
				(type default)
			)
			(layer "F.Fab")
		)
		(fp_line
			(start 0.12065 -0.2794)
			(end 0.12065 -0.3048)
			(stroke
				(width 0.1)
				(type default)
			)
			(layer "F.Fab")
		)
		(fp_line
			(start 0.67945 -0.3048)
			(end 0.67945 0.3048)
			(stroke
				(width 0.1)
				(type default)
			)
			(layer "F.Fab")
		)
		(fp_line
			(start 0.67945 0.3048)
			(end 0.120396 0.3048)
			(stroke
				(width 0.1)
				(type default)
			)
			(layer "F.Fab")
		)
		(pad "1" smd circle
			(at -0.40005 0)
			(size 0 0)
			(layers "F.Cu" "F.Mask" "F.Paste")
			(net "P3V3_AUX")
		)
		(pad "2" smd circle
			(at 0.40005 0)
			(size 0 0)
			(layers "F.Cu" "F.Mask" "F.Paste")
			(net "SCM_JTAG_MUX_S0")
		)
	)
	(footprint ""
		(layer "F.Cu")
		(at 97.074736 -127.787654 -90)
		(property "Reference" "R1459"
			(at 0 0 270)
			(layer "F.SilkS")
			(hide yes)
			(effects
				(font
					(size 1.27 1.27)
				)
			)
		)
		(property "Value" ""
			(at 0 0 270)
			(layer "F.Fab")
			(effects
				(font
					(size 1.27 1.27)
				)
			)
		)
		(duplicate_pad_numbers_are_jumpers no)
		(fp_line
			(start -0.7874 0.4064)
			(end -0.7874 -0.4064)
			(stroke
				(width 0.1524)
				(type default)
			)
			(layer "F.SilkS")
		)
		(fp_line
			(start 0.7874 0.4064)
			(end -0.7874 0.4064)
			(stroke
				(width 0.1524)
				(type default)
			)
			(layer "F.SilkS")
		)
		(fp_line
			(start -0.7874 -0.4064)
			(end 0.7874 -0.4064)
			(stroke
				(width 0.1524)
				(type default)
			)
			(layer "F.SilkS")
		)
		(fp_line
			(start 0.7874 -0.4064)
			(end 0.7874 0.4064)
			(stroke
				(width 0.1524)
				(type default)
			)
			(layer "F.SilkS")
		)
		(fp_line
			(start -0.67945 0.3048)
			(end -0.67945 -0.305054)
			(stroke
				(width 0.1)
				(type default)
			)
			(layer "F.Fab")
		)
		(fp_line
			(start -0.12065 0.3048)
			(end -0.67945 0.3048)
			(stroke
				(width 0.1)
				(type default)
			)
			(layer "F.Fab")
		)
		(fp_line
			(start 0.120396 0.3048)
			(end 0.120396 0.2794)
			(stroke
				(width 0.1)
				(type default)
			)
			(layer "F.Fab")
		)
		(fp_line
			(start 0.67945 0.3048)
			(end 0.120396 0.3048)
			(stroke
				(width 0.1)
				(type default)
			)
			(layer "F.Fab")
		)
		(fp_line
			(start -0.12065 0.2794)
			(end -0.12065 0.3048)
			(stroke
				(width 0.1)
				(type default)
			)
			(layer "F.Fab")
		)
		(fp_line
			(start 0.120396 0.2794)
			(end -0.12065 0.2794)
			(stroke
				(width 0.1)
				(type default)
			)
			(layer "F.Fab")
		)
		(fp_line
			(start -0.12065 -0.2794)
			(end 0.12065 -0.2794)
			(stroke
				(width 0.1)
				(type default)
			)
			(layer "F.Fab")
		)
		(fp_line
			(start 0.12065 -0.2794)
			(end 0.12065 -0.3048)
			(stroke
				(width 0.1)
				(type default)
			)
			(layer "F.Fab")
		)
		(fp_line
			(start 0.12065 -0.3048)
			(end 0.67945 -0.3048)
			(stroke
				(width 0.1)
				(type default)
			)
			(layer "F.Fab")
		)
		(fp_line
			(start 0.67945 -0.3048)
			(end 0.67945 0.3048)
			(stroke
				(width 0.1)
				(type default)
			)
			(layer "F.Fab")
		)
		(fp_line
			(start -0.67945 -0.305054)
			(end -0.12065 -0.305054)
			(stroke
				(width 0.1)
				(type default)
			)
			(layer "F.Fab")
		)
		(fp_line
			(start -0.12065 -0.305054)
			(end -0.12065 -0.2794)
			(stroke
				(width 0.1)
				(type default)
			)
			(layer "F.Fab")
		)
		(pad "1" smd circle
			(at -0.40005 0 270)
			(size 0 0)
			(layers "F.Cu" "F.Mask" "F.Paste")
			(net "PWRGD_P12V_MEM_CPU1")
		)
		(pad "2" smd circle
			(at 0.40005 0 270)
			(size 0 0)
			(layers "F.Cu" "F.Mask" "F.Paste")
			(net "PWRGD_P12V_MEM_CPU1_R")
		)
	)
)
